# S9S_MB_2U (Grand Teton) — schematic netlist excerpt (pin names and nets, part order shuffled) for the footprints in the layout excerpt that follows; sources: Cadence DE-HDL packaged netlist, KiCad conversion of 03242023_DA0F0TMBIJ0_F0T_Motherboard_J_brd_V01_OCP.brd

R3490  Q_RES  4.7K 5% CHIP  pkg 0402LF  page 150 : A = P3V3_AUX ; B = GPU_FPGA_EROT_RECOV_N
C880  Q_CAP_DIFFBUS  DIFF BUS_0.22UF 6.3V 20% X6S  pkg C0201  page 174 : \1\ = P5E_CPU0_PE3_TX_C_DN<10> ; \2\ = P5E_CPU0_PE3_TX_DN<10>
R4210  Q_RES  200K 1% EMPTY  pkg 0402LF  page 170 : A = P3V3_AUX ; B = FM_THERMAL_ALERT_N

(kicad_pcb
	(version 20260206)
	(generator "pcbnew")
	(generator_version "10.0")
	(general
		(thickness 1.6)
		(legacy_teardrops no)
	)
	(paper "A4")
	(title_block
		(title "03242023_DA0F0TMBIJ0_F0T_Motherboard_J_brd_V01_OCP.brd")
		(comment 1 "Grand Teton / footprints 1158-1160 of 6105")
	)
	(layers
		(0 "F.Cu" signal "TOP")
		(4 "In1.Cu" signal "GND")
		(6 "In2.Cu" signal "IN1")
		(8 "In3.Cu" signal "GND1")
		(10 "In4.Cu" signal "IN2")
		(12 "In5.Cu" signal "GND2")
		(14 "In6.Cu" signal "IN3")
		(16 "In7.Cu" signal "GND3")
		(18 "In8.Cu" signal "VCC")
		(20 "In9.Cu" signal "VCC1")
		(22 "In10.Cu" signal "GND4")
		(24 "In11.Cu" signal "IN4")
		(26 "In12.Cu" signal "GND5")
		(28 "In13.Cu" signal "IN5")
		(30 "In14.Cu" signal "GND6")
		(32 "In15.Cu" signal "IN6")
		(34 "In16.Cu" signal "GND7")
		(2 "B.Cu" signal "BOTTOM")
		(9 "F.Adhes" user "F.Adhesive")
		(11 "B.Adhes" user "B.Adhesive")
		(13 "F.Paste" user "Package Geometry/Pastemask Top")
		(15 "B.Paste" user "Package Geometry/Pastemask Bottom")
		(5 "F.SilkS" user "Ref Des/Silkscreen Top")
		(7 "B.SilkS" user "Ref Des/Silkscreen Bottom")
		(1 "F.Mask" user "Board Geometry/Soldermask Top")
		(3 "B.Mask" user "Board Geometry/Soldermask Bottom")
		(17 "Dwgs.User" user "User.Drawings")
		(19 "Cmts.User" user "User.Comments")
		(21 "Eco1.User" user "User.Eco1")
		(23 "Eco2.User" user "User.Eco2")
		(25 "Edge.Cuts" user "Board Geometry/Outline")
		(27 "Margin" user)
		(31 "F.CrtYd" user "Package Geometry/Place Bound Top")
		(29 "B.CrtYd" user "Package Geometry/Place Bound Bottom")
		(35 "F.Fab" user "Ref Des/Assembly Top")
		(33 "B.Fab" user "Ref Des/Assembly Bottom")
	)
	(footprint ""
		(layer "F.Cu")
		(at 108.85043 -401.184364)
		(property "Reference" "R3490"
			(at 0 0 0)
			(layer "F.SilkS")
			(hide yes)
			(effects
				(font
					(size 1.27 1.27)
				)
			)
		)
		(property "Value" ""
			(at 0 0 0)
			(layer "F.Fab")
			(effects
				(font
					(size 1.27 1.27)
				)
			)
		)
		(duplicate_pad_numbers_are_jumpers no)
		(fp_line
			(start -0.7874 -0.4064)
			(end 0.7874 -0.4064)
			(stroke
				(width 0.1524)
				(type default)
			)
			(layer "F.SilkS")
		)
		(fp_line
			(start -0.7874 0.4064)
			(end -0.7874 -0.4064)
			(stroke
				(width 0.1524)
				(type default)
			)
			(layer "F.SilkS")
		)
		(fp_line
			(start 0.7874 -0.4064)
			(end 0.7874 0.4064)
			(stroke
				(width 0.1524)
				(type default)
			)
			(layer "F.SilkS")
		)
		(fp_line
			(start 0.7874 0.4064)
			(end -0.7874 0.4064)
			(stroke
				(width 0.1524)
				(type default)
			)
			(layer "F.SilkS")
		)
		(fp_line
			(start -0.67945 -0.305054)
			(end -0.12065 -0.305054)
			(stroke
				(width 0.1)
				(type default)
			)
			(layer "F.Fab")
		)
		(fp_line
			(start -0.67945 0.3048)
			(end -0.67945 -0.305054)
			(stroke
				(width 0.1)
				(type default)
			)
			(layer "F.Fab")
		)
		(fp_line
			(start -0.12065 -0.305054)
			(end -0.12065 -0.2794)
			(stroke
				(width 0.1)
				(type default)
			)
			(layer "F.Fab")
		)
		(fp_line
			(start -0.12065 -0.2794)
			(end 0.12065 -0.2794)
			(stroke
				(width 0.1)
				(type default)
			)
			(layer "F.Fab")
		)
		(fp_line
			(start -0.12065 0.2794)
			(end -0.12065 0.3048)
			(stroke
				(width 0.1)
				(type default)
			)
			(layer "F.Fab")
		)
		(fp_line
			(start -0.12065 0.3048)
			(end -0.67945 0.3048)
			(stroke
				(width 0.1)
				(type default)
			)
			(layer "F.Fab")
		)
		(fp_line
			(start 0.120396 0.2794)
			(end -0.12065 0.2794)
			(stroke
				(width 0.1)
				(type default)
			)
			(layer "F.Fab")
		)
		(fp_line
			(start 0.120396 0.3048)
			(end 0.120396 0.2794)
			(stroke
				(width 0.1)
				(type default)
			)
			(layer "F.Fab")
		)
		(fp_line
			(start 0.12065 -0.3048)
			(end 0.67945 -0.3048)
			(stroke
				(width 0.1)
				(type default)
			)
			(layer "F.Fab")
		)
		(fp_line
			(start 0.12065 -0.2794)
			(end 0.12065 -0.3048)
			(stroke
				(width 0.1)
				(type default)
			)
			(layer "F.Fab")
		)
		(fp_line
			(start 0.67945 -0.3048)
			(end 0.67945 0.3048)
			(stroke
				(width 0.1)
				(type default)
			)
			(layer "F.Fab")
		)
		(fp_line
			(start 0.67945 0.3048)
			(end 0.120396 0.3048)
			(stroke
				(width 0.1)
				(type default)
			)
			(layer "F.Fab")
		)
		(pad "1" smd circle
			(at -0.40005 0)
			(size 0 0)
			(layers "F.Cu" "F.Mask" "F.Paste")
			(net "P3V3_AUX")
		)
		(pad "2" smd circle
			(at 0.40005 0)
			(size 0 0)
			(layers "F.Cu" "F.Mask" "F.Paste")
			(net "GPU_FPGA_EROT_RECOV_N")
		)
	)
	(footprint ""
		(layer "F.Cu")
		(at 104.503728 -426.787818)
		(property "Reference" "R4210"
			(at 0 0 0)
			(layer "F.SilkS")
			(hide yes)
			(effects
				(font
					(size 1.27 1.27)
				)
			)
		)
		(property "Value" ""
			(at 0 0 0)
			(layer "F.Fab")
			(effects
				(font
					(size 1.27 1.27)
				)
			)
		)
		(duplicate_pad_numbers_are_jumpers no)
		(fp_line
			(start -0.7874 -0.4064)
			(end 0.7874 -0.4064)
			(stroke
				(width 0.1524)
				(type default)
			)
			(layer "F.SilkS")
		)
		(fp_line
			(start -0.7874 0.4064)
			(end -0.7874 -0.4064)
			(stroke
				(width 0.1524)
				(type default)
			)
			(layer "F.SilkS")
		)
		(fp_line
			(start 0.7874 -0.4064)
			(end 0.7874 0.4064)
			(stroke
				(width 0.1524)
				(type default)
			)
			(layer "F.SilkS")
		)
		(fp_line
			(start 0.7874 0.4064)
			(end -0.7874 0.4064)
			(stroke
				(width 0.1524)
				(type default)
			)
			(layer "F.SilkS")
		)
		(fp_line
			(start -0.67945 -0.305054)
			(end -0.12065 -0.305054)
			(stroke
				(width 0.1)
				(type default)
			)
			(layer "F.Fab")
		)
		(fp_line
			(start -0.67945 0.3048)
			(end -0.67945 -0.305054)
			(stroke
				(width 0.1)
				(type default)
			)
			(layer "F.Fab")
		)
		(fp_line
			(start -0.12065 -0.305054)
			(end -0.12065 -0.2794)
			(stroke
				(width 0.1)
				(type default)
			)
			(layer "F.Fab")
		)
		(fp_line
			(start -0.12065 -0.2794)
			(end 0.12065 -0.2794)
			(stroke
				(width 0.1)
				(type default)
			)
			(layer "F.Fab")
		)
		(fp_line
			(start -0.12065 0.2794)
			(end -0.12065 0.3048)
			(stroke
				(width 0.1)
				(type default)
			)
			(layer "F.Fab")
		)
		(fp_line
			(start -0.12065 0.3048)
			(end -0.67945 0.3048)
			(stroke
				(width 0.1)
				(type default)
			)
			(layer "F.Fab")
		)
		(fp_line
			(start 0.120396 0.2794)
			(end -0.12065 0.2794)
			(stroke
				(width 0.1)
				(type default)
			)
			(layer "F.Fab")
		)
		(fp_line
			(start 0.120396 0.3048)
			(end 0.120396 0.2794)
			(stroke
				(width 0.1)
				(type default)
			)
			(layer "F.Fab")
		)
		(fp_line
			(start 0.12065 -0.3048)
			(end 0.67945 -0.3048)
			(stroke
				(width 0.1)
				(type default)
			)
			(layer "F.Fab")
		)
		(fp_line
			(start 0.12065 -0.2794)
			(end 0.12065 -0.3048)
			(stroke
				(width 0.1)
				(type default)
			)
			(layer "F.Fab")
		)
		(fp_line
			(start 0.67945 -0.3048)
			(end 0.67945 0.3048)
			(stroke
				(width 0.1)
				(type default)
			)
			(layer "F.Fab")
		)
		(fp_line
			(start 0.67945 0.3048)
			(end 0.120396 0.3048)
			(stroke
				(width 0.1)
				(type default)
			)
			(layer "F.Fab")
		)
		(pad "1" smd circle
			(at -0.40005 0)
			(size 0 0)
			(layers "F.Cu" "F.Mask" "F.Paste")
			(net "P3V3_AUX")
		)
		(pad "2" smd circle
			(at 0.40005 0)
			(size 0 0)
			(layers "F.Cu" "F.Mask" "F.Paste")
			(net "FM_THERMAL_ALERT_N")
		)
	)
	(footprint ""
		(layer "F.Cu")
		(at 388.05993 -408.517344 -90)
		(property "Reference" "C880"
			(at 0 0 270)
			(layer "F.SilkS")
			(hide yes)
			(effects
				(font
					(size 1.27 1.27)
				)
			)
		)
		(property "Value" ""
			(at 0 0 270)
			(layer "F.Fab")
			(effects
				(font
					(size 1.27 1.27)
				)
			)
		)
		(duplicate_pad_numbers_are_jumpers no)
		(fp_line
			(start -0.299974 0.150114)
			(end -0.299974 -0.150114)
			(stroke
				(width 0.1)
				(type default)
			)
			(layer "F.Fab")
		)
		(fp_line
			(start 0.299974 0.150114)
			(end -0.299974 0.150114)
			(stroke
				(width 0.1)
				(type default)
			)
			(layer "F.Fab")
		)
		(fp_line
			(start -0.299974 -0.150114)
			(end 0.299974 -0.150114)
			(stroke
				(width 0.1)
				(type default)
			)
			(layer "F.Fab")
		)
		(fp_line
			(start 0.299974 -0.150114)
			(end 0.299974 0.150114)
			(stroke
				(width 0.1)
				(type default)
			)
			(layer "F.Fab")
		)
		(pad "1" smd rect
			(at -0.2667 0 270)
			(size 0.3048 0.381)
			(layers "F.Cu" "F.Mask" "F.Paste")
			(net "P5E_CPU0_PE3_TX_C_DN<10>")
		)
		(pad "2" smd rect
			(at 0.2667 0 270)
			(size 0.3048 0.381)
			(layers "F.Cu" "F.Mask" "F.Paste")
			(net "P5E_CPU0_PE3_TX_DN<10>")
		)
	)
)
